(kicad_pcb
	(version 20260206)
	(generator "pcbnew")
	(generator_version "10.0")
	(general
		(thickness 1.6)
		(legacy_teardrops no)
	)
	(paper "A4")
	(title_block
		(title "fcb — 12433-1M.1206WZS1330.brd")
		(comment 1 "Open Vault / Knox (Wiwynn) / footprints 405-411 of 495")
	)
	(layers
		(0 "F.Cu" signal "TOP")
		(4 "In1.Cu" signal "L2GND")
		(6 "In2.Cu" signal "L3VCC")
		(2 "B.Cu" signal "BOTTOM")
		(9 "F.Adhes" user "F.Adhesive")
		(11 "B.Adhes" user "B.Adhesive")
		(13 "F.Paste" user "Package Geometry/Pastemask Top")
		(15 "B.Paste" user "Package Geometry/Pastemask Bottom")
		(5 "F.SilkS" user "Ref Des/Silkscreen Top")
		(7 "B.SilkS" user "Ref Des/Silkscreen Bottom")
		(1 "F.Mask" user "Board Geometry/Soldermask Top")
		(3 "B.Mask" user "Board Geometry/Soldermask Bottom")
		(17 "Dwgs.User" user "User.Drawings")
		(19 "Cmts.User" user "User.Comments")
		(21 "Eco1.User" user "User.Eco1")
		(23 "Eco2.User" user "User.Eco2")
		(25 "Edge.Cuts" user "Board Geometry/Outline")
		(27 "Margin" user)
		(31 "F.CrtYd" user "Package Geometry/Place Bound Top")
		(29 "B.CrtYd" user "Package Geometry/Place Bound Bottom")
		(35 "F.Fab" user "Ref Des/Assembly Top")
		(33 "B.Fab" user "Ref Des/Assembly Bottom")
	)
	(footprint ""
		(layer "F.Cu")
		(at 23.749 -101.219 90)
		(property "Reference" "TC4"
			(at 0 0 90)
			(layer "F.SilkS")
			(hide yes)
			(effects
				(font
					(size 1.27 1.27)
				)
			)
		)
		(property "Value" "ST15U25VDM-1-GP"
			(at 0 -9.6012 90)
			(unlocked yes)
			(layer "F.Fab")
			(hide yes)
			(effects
				(font
					(size 1.016 1.016)
					(thickness 0.1524)
				)
			)
		)
		(property "Device Type" "CT7343H79"
			(at 0 -11.1252 90)
			(unlocked yes)
			(layer "F.Fab")
			(hide yes)
			(effects
				(font
					(size 1.016 1.016)
					(thickness 0.1524)
				)
			)
		)
		(duplicate_pad_numbers_are_jumpers no)
		(fp_line
			(start 2.286 -4.8768)
			(end -2.286 -4.8768)
			(stroke
				(width 0.1524)
				(type default)
			)
			(layer "F.SilkS")
		)
		(fp_line
			(start -2.286 -4.8768)
			(end -2.286 -2.032)
			(stroke
				(width 0.1524)
				(type default)
			)
			(layer "F.SilkS")
		)
		(fp_line
			(start 2.1082 -4.699)
			(end -2.1082 -4.699)
			(stroke
				(width 0.508)
				(type default)
			)
			(layer "F.SilkS")
		)
		(fp_line
			(start 2.286 -2.032)
			(end 2.286 -4.8768)
			(stroke
				(width 0.1524)
				(type default)
			)
			(layer "F.SilkS")
		)
		(fp_line
			(start 2.286 2.032)
			(end 2.286 4.8768)
			(stroke
				(width 0.1524)
				(type default)
			)
			(layer "F.SilkS")
		)
		(fp_line
			(start 2.286 4.8768)
			(end -2.286 4.8768)
			(stroke
				(width 0.1524)
				(type default)
			)
			(layer "F.SilkS")
		)
		(fp_line
			(start -2.286 4.8768)
			(end -2.286 2.032)
			(stroke
				(width 0.1524)
				(type default)
			)
			(layer "F.SilkS")
		)
		(fp_rect
			(start -2.1463 3.6449)
			(end 2.1463 -3.6449)
			(stroke
				(width 0)
				(type default)
			)
			(fill no)
			(layer "F.CrtYd")
		)
		(fp_poly
			(pts
				(xy -2.54 4.953) (xy -2.54 4.2926) (xy -3.81 4.2926) (xy -3.81 -4.2926) (xy -2.54 -4.2926) (xy -2.54 -4.953)
				(xy 2.54 -4.953) (xy 2.54 -4.2926) (xy 3.81 -4.2926) (xy 3.81 -1.6256) (xy 2.1463 -1.6256) (xy 2.1463 -3.6449)
				(xy -2.1463 -3.6449) (xy -2.1463 3.6449) (xy 2.1463 3.6449) (xy 2.1463 -1.6129) (xy 3.81 -1.6129)
				(xy 3.81 4.2926) (xy 2.54 4.2926) (xy 2.54 4.953)
			)
			(stroke
				(width 0)
				(type default)
			)
			(fill no)
			(layer "F.CrtYd")
		)
		(fp_rect
			(start 2.54 4.2926)
			(end 3.81 -4.2926)
			(stroke
				(width 0)
				(type default)
			)
			(fill no)
			(layer "F.Fab")
		)
		(fp_rect
			(start -3.81 4.2926)
			(end -2.54 -4.2926)
			(stroke
				(width 0)
				(type default)
			)
			(fill no)
			(layer "F.Fab")
		)
		(fp_rect
			(start -2.54 4.953)
			(end 2.54 -4.953)
			(stroke
				(width 0)
				(type default)
			)
			(fill no)
			(layer "F.Fab")
		)
		(pad "1" smd rect
			(at 0 -3.1496 90)
			(size 2.413 2.286)
			(layers "F.Cu" "F.Mask" "F.Paste")
			(net "P12VU")
		)
		(pad "2" smd rect
			(at 0 3.1496 90)
			(size 2.413 2.286)
			(layers "F.Cu" "F.Mask" "F.Paste")
			(net "GND")
		)
		(zone
			(layer "F.Cu")
			(hatch none 0.5)
			(connect_pads
				(clearance 0)
			)
			(min_thickness 0.25)
			(keepout
				(tracks allowed)
				(vias not_allowed)
				(pads allowed)
				(copperpour not_allowed)
				(footprints allowed)
			)
			(placement
				(enabled no)
				(sheetname "")
			)
			(fill
				(thermal_gap 0.5)
				(thermal_bridge_width 0.5)
				(island_removal_mode 0)
			)
			(polygon
				(pts
					(xy 22.0599 -102.7303) (xy 19.1516 -102.7303) (xy 19.1516 -99.7077) (xy 22.0472 -99.7077) (xy 22.3774 -99.7077)
					(xy 22.3774 -102.7303)
				)
			)
		)
		(zone
			(layer "F.Cu")
			(hatch none 0.5)
			(connect_pads
				(clearance 0)
			)
			(min_thickness 0.25)
			(keepout
				(tracks allowed)
				(vias not_allowed)
				(pads allowed)
				(copperpour not_allowed)
				(footprints allowed)
			)
			(placement
				(enabled no)
				(sheetname "")
			)
			(fill
				(thermal_gap 0.5)
				(thermal_bridge_width 0.5)
				(island_removal_mode 0)
			)
			(polygon
				(pts
					(xy 28.3464 -99.7077) (xy 28.3464 -102.7303) (xy 25.4508 -102.7303) (xy 25.1206 -102.7303) (xy 25.1206 -99.7077)
					(xy 25.4508 -99.7077)
				)
			)
		)
	)
	(footprint ""
		(layer "F.Cu")
		(at 13.6652 -256.8702)
		(property "Reference" "C38"
			(at 0 0 0)
			(layer "F.SilkS")
			(hide yes)
			(effects
				(font
					(size 1.27 1.27)
				)
			)
		)
		(property "Value" "SCD1U16V2KX-3GP"
			(at 1.1811 -2.7051 0)
			(unlocked yes)
			(layer "F.Fab")
			(hide yes)
			(effects
				(font
					(size 1.016 1.016)
					(thickness 0.1524)
				)
			)
		)
		(property "Device Type" "C402H22"
			(at 1.1811 -4.2291 0)
			(unlocked yes)
			(layer "F.Fab")
			(hide yes)
			(effects
				(font
					(size 1.016 1.016)
					(thickness 0.1524)
				)
			)
		)
		(duplicate_pad_numbers_are_jumpers no)
		(fp_rect
			(start -0.4318 0.9525)
			(end 0.4318 -0.9525)
			(stroke
				(width 0)
				(type default)
			)
			(fill no)
			(layer "F.CrtYd")
		)
		(fp_rect
			(start -0.4318 0.9525)
			(end 0.4318 -0.9525)
			(stroke
				(width 0)
				(type default)
			)
			(fill no)
			(layer "F.Fab")
		)
		(pad "1" smd custom
			(at 0 -0.4445)
			(size 0.1524 0.1524)
			(layers "F.Cu" "F.Mask" "F.Paste")
			(net "FAN_TACH5")
			(options
				(clearance outline)
				(anchor circle)
			)
			(primitives
				(gr_poly
					(pts
						(arc
							(start 0.3048 -0.2032)
							(mid 0.275042 -0.275042)
							(end 0.2032 -0.3048)
						)
						(arc
							(start -0.2032 -0.3048)
							(mid -0.275042 -0.275042)
							(end -0.3048 -0.2032)
						)
						(arc
							(start -0.3048 0.2032)
							(mid -0.275042 0.275042)
							(end -0.2032 0.3048)
						)
						(arc
							(start 0.2032 0.3048)
							(mid 0.275042 0.275042)
							(end 0.3048 0.2032)
						)
					)
					(width 0)
					(fill yes)
				)
			)
		)
		(pad "2" smd custom
			(at 0 0.4445)
			(size 0.1524 0.1524)
			(layers "F.Cu" "F.Mask" "F.Paste")
			(net "GND")
			(options
				(clearance outline)
				(anchor circle)
			)
			(primitives
				(gr_poly
					(pts
						(arc
							(start 0.3048 -0.2032)
							(mid 0.275042 -0.275042)
							(end 0.2032 -0.3048)
						)
						(arc
							(start -0.2032 -0.3048)
							(mid -0.275042 -0.275042)
							(end -0.3048 -0.2032)
						)
						(arc
							(start -0.3048 0.2032)
							(mid -0.275042 0.275042)
							(end -0.2032 0.3048)
						)
						(arc
							(start 0.2032 0.3048)
							(mid 0.275042 0.275042)
							(end 0.3048 0.2032)
						)
					)
					(width 0)
					(fill yes)
				)
			)
		)
	)
	(footprint ""
		(layer "F.Cu")
		(at 38.361366 -159.40151 90)
		(property "Reference" "TP15"
			(at 0 0 90)
			(layer "F.SilkS")
			(hide yes)
			(effects
				(font
					(size 1.27 1.27)
				)
			)
		)
		(property "Value" "TPAD32-GP"
			(at 0 -3.166364 90)
			(unlocked yes)
			(layer "F.Fab")
			(hide yes)
			(effects
				(font
					(size 1.016 1.016)
					(thickness 0.1524)
				)
			)
		)
		(property "Device Type" "TPAD32"
			(at 0 -4.690618 90)
			(unlocked yes)
			(layer "F.Fab")
			(hide yes)
			(effects
				(font
					(size 1.016 1.016)
					(thickness 0.1524)
				)
			)
		)
		(duplicate_pad_numbers_are_jumpers no)
		(fp_poly
			(pts
				(arc
					(start 0 0.7112)
					(mid 0 -0.7112)
					(end 0 0.7112)
				)
			)
			(stroke
				(width 0)
				(type default)
			)
			(fill no)
			(layer "F.CrtYd")
		)
		(fp_poly
			(pts
				(arc
					(start 0 0.7112)
					(mid 0 -0.7112)
					(end 0 0.7112)
				)
			)
			(stroke
				(width 0)
				(type default)
			)
			(fill no)
			(layer "F.Fab")
		)
		(pad "1" smd circle
			(at 0 0 90)
			(size 0.8128 0.8128)
			(layers "F.Cu" "F.Mask" "F.Paste")
			(net "NCT7904_THERMTRIP")
		)
	)
	(footprint ""
		(layer "F.Cu")
		(at 26.1366 -210.844384 180)
		(property "Reference" "R136"
			(at 0 0 180)
			(layer "F.SilkS")
			(hide yes)
			(effects
				(font
					(size 1.27 1.27)
				)
			)
		)
		(property "Value" "0R2J-2-GP"
			(at 0.064008 -3.993896 180)
			(unlocked yes)
			(layer "F.Fab")
			(hide yes)
			(effects
				(font
					(size 1.016 1.016)
					(thickness 0.1524)
				)
			)
		)
		(property "Device Type" "R402H16"
			(at 0.064008 -5.517896 180)
			(unlocked yes)
			(layer "F.Fab")
			(hide yes)
			(effects
				(font
					(size 1.016 1.016)
					(thickness 0.1524)
				)
			)
		)
		(duplicate_pad_numbers_are_jumpers no)
		(fp_line
			(start 0.508 -0.9398)
			(end -0.508 -0.9398)
			(stroke
				(width 0.1524)
				(type default)
			)
			(layer "F.SilkS")
		)
		(fp_line
			(start -0.508 -0.9398)
			(end -0.508 0.9398)
			(stroke
				(width 0.1524)
				(type default)
			)
			(layer "F.SilkS")
		)
		(fp_rect
			(start -0.508 0.9398)
			(end 0.508 -0.9398)
			(stroke
				(width 0)
				(type default)
			)
			(fill no)
			(layer "F.CrtYd")
		)
		(fp_rect
			(start -0.508 0.9398)
			(end 0.508 -0.9398)
			(stroke
				(width 0)
				(type default)
			)
			(fill no)
			(layer "F.Fab")
		)
		(pad "1" smd custom
			(at 0 -0.4445 180)
			(size 0.1397 0.1397)
			(layers "F.Cu" "F.Mask" "F.Paste")
			(net "PWM_OUT_FAN6_NET")
			(options
				(clearance outline)
				(anchor circle)
			)
			(primitives
				(gr_poly
					(pts
						(arc
							(start -0.1778 -0.2794)
							(mid -0.249642 -0.249642)
							(end -0.2794 -0.1778)
						)
						(arc
							(start -0.2794 0.1778)
							(mid -0.249642 0.249642)
							(end -0.1778 0.2794)
						)
						(arc
							(start 0.1778 0.2794)
							(mid 0.249642 0.249642)
							(end 0.2794 0.1778)
						)
						(arc
							(start 0.2794 -0.1778)
							(mid 0.249642 -0.249642)
							(end 0.1778 -0.2794)
						)
					)
					(width 0)
					(fill yes)
				)
			)
		)
		(pad "2" smd custom
			(at 0 0.4445 180)
			(size 0.1397 0.1397)
			(layers "F.Cu" "F.Mask" "F.Paste")
			(net "PWM_OUT_FAN6")
			(options
				(clearance outline)
				(anchor circle)
			)
			(primitives
				(gr_poly
					(pts
						(arc
							(start -0.1778 -0.2794)
							(mid -0.249642 -0.249642)
							(end -0.2794 -0.1778)
						)
						(arc
							(start -0.2794 0.1778)
							(mid -0.249642 0.249642)
							(end -0.1778 0.2794)
						)
						(arc
							(start 0.1778 0.2794)
							(mid 0.249642 0.249642)
							(end 0.2794 0.1778)
						)
						(arc
							(start 0.2794 -0.1778)
							(mid 0.249642 -0.249642)
							(end 0.1778 -0.2794)
						)
					)
					(width 0)
					(fill yes)
				)
			)
		)
	)
	(footprint ""
		(layer "F.Cu")
		(at 36.6522 -282.9814)
		(property "Reference" "C48"
			(at 0 0 0)
			(layer "F.SilkS")
			(hide yes)
			(effects
				(font
					(size 1.27 1.27)
				)
			)
		)
		(property "Value" "SC1U25V3KX-1-GP"
			(at 0 -2.8194 0)
			(unlocked yes)
			(layer "F.Fab")
			(hide yes)
			(effects
				(font
					(size 1.016 1.016)
					(thickness 0.1524)
				)
			)
		)
		(property "Device Type" "C603H36"
			(at 0 -4.3434 0)
			(unlocked yes)
			(layer "F.Fab")
			(hide yes)
			(effects
				(font
					(size 1.016 1.016)
					(thickness 0.1524)
				)
			)
		)
		(duplicate_pad_numbers_are_jumpers no)
		(fp_line
			(start 0.508 0)
			(end -0.508 0)
			(stroke
				(width 0.2032)
				(type default)
			)
			(layer "F.SilkS")
		)
		(fp_rect
			(start -0.5842 1.3335)
			(end 0.5842 -1.3335)
			(stroke
				(width 0)
				(type default)
			)
			(fill no)
			(layer "F.CrtYd")
		)
		(fp_rect
			(start -0.5842 1.3335)
			(end 0.5842 -1.3335)
			(stroke
				(width 0)
				(type default)
			)
			(fill no)
			(layer "F.Fab")
		)
		(pad "1" smd custom
			(at 0 -0.762)
			(size 0.2159 0.2159)
			(layers "F.Cu" "F.Mask" "F.Paste")
			(net "P12V")
			(options
				(clearance outline)
				(anchor circle)
			)
			(primitives
				(gr_poly
					(pts
						(arc
							(start -0.3302 -0.4318)
							(mid -0.402042 -0.402042)
							(end -0.4318 -0.3302)
						)
						(arc
							(start -0.4318 0.3302)
							(mid -0.402042 0.402042)
							(end -0.3302 0.4318)
						)
						(arc
							(start 0.3302 0.4318)
							(mid 0.402042 0.402042)
							(end 0.4318 0.3302)
						)
						(arc
							(start 0.4318 -0.3302)
							(mid 0.402042 -0.402042)
							(end 0.3302 -0.4318)
						)
					)
					(width 0)
					(fill yes)
				)
			)
		)
		(pad "2" smd custom
			(at 0 0.762)
			(size 0.2159 0.2159)
			(layers "F.Cu" "F.Mask" "F.Paste")
			(net "GND")
			(options
				(clearance outline)
				(anchor circle)
			)
			(primitives
				(gr_poly
					(pts
						(arc
							(start -0.3302 -0.4318)
							(mid -0.402042 -0.402042)
							(end -0.4318 -0.3302)
						)
						(arc
							(start -0.4318 0.3302)
							(mid -0.402042 0.402042)
							(end -0.3302 0.4318)
						)
						(arc
							(start 0.3302 0.4318)
							(mid 0.402042 0.402042)
							(end 0.4318 0.3302)
						)
						(arc
							(start 0.4318 -0.3302)
							(mid 0.402042 -0.402042)
							(end 0.3302 -0.4318)
						)
					)
					(width 0)
					(fill yes)
				)
			)
		)
	)
	(footprint ""
		(layer "F.Cu")
		(at 14.8844 -41.4782 90)
		(property "Reference" "R116"
			(at 0 0 90)
			(layer "F.SilkS")
			(hide yes)
			(effects
				(font
					(size 1.27 1.27)
				)
			)
		)
		(property "Value" "470R2F-GP"
			(at 0.064008 -3.993896 90)
			(unlocked yes)
			(layer "F.Fab")
			(hide yes)
			(effects
				(font
					(size 1.016 1.016)
					(thickness 0.1524)
				)
			)
		)
		(property "Device Type" "R402H16"
			(at 0.064008 -5.517896 90)
			(unlocked yes)
			(layer "F.Fab")
			(hide yes)
			(effects
				(font
					(size 1.016 1.016)
					(thickness 0.1524)
				)
			)
		)
		(duplicate_pad_numbers_are_jumpers no)
		(fp_line
			(start 0.508 -0.9398)
			(end -0.508 -0.9398)
			(stroke
				(width 0.1524)
				(type default)
			)
			(layer "F.SilkS")
		)
		(fp_line
			(start -0.508 -0.9398)
			(end -0.508 0.9398)
			(stroke
				(width 0.1524)
				(type default)
			)
			(layer "F.SilkS")
		)
		(fp_rect
			(start -0.508 0.9398)
			(end 0.508 -0.9398)
			(stroke
				(width 0)
				(type default)
			)
			(fill no)
			(layer "F.CrtYd")
		)
		(fp_rect
			(start -0.508 0.9398)
			(end 0.508 -0.9398)
			(stroke
				(width 0)
				(type default)
			)
			(fill no)
			(layer "F.Fab")
		)
		(pad "1" smd custom
			(at 0 -0.4445 90)
			(size 0.1397 0.1397)
			(layers "F.Cu" "F.Mask" "F.Paste")
			(net "SEB_PEER_1B_HB")
			(options
				(clearance outline)
				(anchor circle)
			)
			(primitives
				(gr_poly
					(pts
						(arc
							(start -0.1778 -0.2794)
							(mid -0.249642 -0.249642)
							(end -0.2794 -0.1778)
						)
						(arc
							(start -0.2794 0.1778)
							(mid -0.249642 0.249642)
							(end -0.1778 0.2794)
						)
						(arc
							(start 0.1778 0.2794)
							(mid 0.249642 0.249642)
							(end 0.2794 0.1778)
						)
						(arc
							(start 0.2794 -0.1778)
							(mid 0.249642 -0.249642)
							(end 0.1778 -0.2794)
						)
					)
					(width 0)
					(fill yes)
				)
			)
		)
		(pad "2" smd custom
			(at 0 0.4445 90)
			(size 0.1397 0.1397)
			(layers "F.Cu" "F.Mask" "F.Paste")
			(net "GND")
			(options
				(clearance outline)
				(anchor circle)
			)
			(primitives
				(gr_poly
					(pts
						(arc
							(start -0.1778 -0.2794)
							(mid -0.249642 -0.249642)
							(end -0.2794 -0.1778)
						)
						(arc
							(start -0.2794 0.1778)
							(mid -0.249642 0.249642)
							(end -0.1778 0.2794)
						)
						(arc
							(start 0.1778 0.2794)
							(mid 0.249642 0.249642)
							(end 0.2794 0.1778)
						)
						(arc
							(start 0.2794 -0.1778)
							(mid 0.249642 -0.249642)
							(end 0.1778 -0.2794)
						)
					)
					(width 0)
					(fill yes)
				)
			)
		)
	)
	(footprint ""
		(layer "F.Cu")
		(at 36.1188 -371.4496 -90)
		(property "Reference" "PR6"
			(at 0 0 270)
			(layer "F.SilkS")
			(hide yes)
			(effects
				(font
					(size 1.27 1.27)
				)
			)
		)
		(property "Value" "100KR2F-L1-GP"
			(at 0.064008 -3.993896 270)
			(unlocked yes)
			(layer "F.Fab")
			(hide yes)
			(effects
				(font
					(size 1.016 1.016)
					(thickness 0.1524)
				)
			)
		)
		(property "Device Type" "R402H16"
			(at 0.064008 -5.517896 270)
			(unlocked yes)
			(layer "F.Fab")
			(hide yes)
			(effects
				(font
					(size 1.016 1.016)
					(thickness 0.1524)
				)
			)
		)
		(duplicate_pad_numbers_are_jumpers no)
		(fp_line
			(start -0.508 -0.9398)
			(end -0.508 0.9398)
			(stroke
				(width 0.1524)
				(type default)
			)
			(layer "F.SilkS")
		)
		(fp_line
			(start 0.508 -0.9398)
			(end -0.508 -0.9398)
			(stroke
				(width 0.1524)
				(type default)
			)
			(layer "F.SilkS")
		)
		(fp_rect
			(start -0.508 0.9398)
			(end 0.508 -0.9398)
			(stroke
				(width 0)
				(type default)
			)
			(fill no)
			(layer "F.CrtYd")
		)
		(fp_rect
			(start -0.508 0.9398)
			(end 0.508 -0.9398)
			(stroke
				(width 0)
				(type default)
			)
			(fill no)
			(layer "F.Fab")
		)
		(pad "1" smd custom
			(at 0 -0.4445 270)
			(size 0.1397 0.1397)
			(layers "F.Cu" "F.Mask" "F.Paste")
			(net "P12V")
			(options
				(clearance outline)
				(anchor circle)
			)
			(primitives
				(gr_poly
					(pts
						(arc
							(start -0.1778 -0.2794)
							(mid -0.249642 -0.249642)
							(end -0.2794 -0.1778)
						)
						(arc
							(start -0.2794 0.1778)
							(mid -0.249642 0.249642)
							(end -0.1778 0.2794)
						)
						(arc
							(start 0.1778 0.2794)
							(mid 0.249642 0.249642)
							(end 0.2794 0.1778)
						)
						(arc
							(start 0.2794 -0.1778)
							(mid 0.249642 -0.249642)
							(end 0.1778 -0.2794)
						)
					)
					(width 0)
					(fill yes)
				)
			)
		)
		(pad "2" smd custom
			(at 0 0.4445 270)
			(size 0.1397 0.1397)
			(layers "F.Cu" "F.Mask" "F.Paste")
			(net "ADM1276_FLB")
			(options
				(clearance outline)
				(anchor circle)
			)
			(primitives
				(gr_poly
					(pts
						(arc
							(start -0.1778 -0.2794)
							(mid -0.249642 -0.249642)
							(end -0.2794 -0.1778)
						)
						(arc
							(start -0.2794 0.1778)
							(mid -0.249642 0.249642)
							(end -0.1778 0.2794)
						)
						(arc
							(start 0.1778 0.2794)
							(mid 0.249642 0.249642)
							(end 0.2794 0.1778)
						)
						(arc
							(start 0.2794 -0.1778)
							(mid 0.249642 -0.249642)
							(end 0.1778 -0.2794)
						)
					)
					(width 0)
					(fill yes)
				)
			)
		)
	)
)
